#ISCELL
  pure_quanta quanta_title_block_c *
  *
#CELL
  pure_quanta socket4677_azif0045p001c01cs *
  page16_i1
#ISCELL
  standard offpage *
  page16_i10
#ISCELL
  standard offpage *
  page16_i11
#ISCELL
  standard offpage *
  page16_i12
#ISCELL
  standard offpage *
  page16_i16
#ISCELL
  standard offpage *
  page16_i18
#CELL
  pure_quanta q_res *
  page16_i19
#ISCELL
  standard offpage *
  page16_i2
#CELL
  pure_quanta q_res *
  page16_i20
#ISCELL
  standard offpage *
  page16_i21
#ISCELL
  standard offpage *
  page16_i23
#ISCELL
  standard offpage *
  page16_i24
#CELL
  pure_quanta q_res *
  page16_i25
#CELL
  pure_quanta q_res *
  page16_i26
#ISCELL
  logical_power universal_power *
  page16_i28
#ISCELL
  standard offpage *
  page16_i29
#ISCELL
  standard offpage *
  page16_i3
#ISCELL
  standard offpage *
  page16_i30
#CELL
  pure_quanta q_res *
  page16_i31
#CELL
  pure_quanta q_res *
  page16_i32
#ISCELL
  standard offpage *
  page16_i33
#ISCELL
  standard offpage *
  page16_i34
#CELL
  pure_quanta q_res *
  page16_i35
#CELL
  pure_quanta q_res *
  page16_i36
#ISCELL
  standard offpage *
  page16_i4
#ISCELL
  standard offpage *
  page16_i5
#ISCELL
  standard offpage *
  page16_i6
#ISCELL
  standard offpage *
  page16_i7
#ISCELL
  standard offpage *
  page16_i8
#ISCELL
  standard offpage *
  page16_i9
